(kicad_pcb
	(version 20260206)
	(generator "pcbnew")
	(generator_version "10.0")
	(general
		(thickness 1.6)
		(legacy_teardrops no)
	)
	(paper "A4")
	(title_block
		(title "v1-chassis-manager — T6M_CM_d_v01_1031_1645.brd")
		(comment 1 "Open CloudServer (Microsoft) / footprints 842-844 of 2512")
	)
	(layers
		(0 "F.Cu" signal "TOP")
		(4 "In1.Cu" signal "GND1")
		(6 "In2.Cu" signal "IN1")
		(8 "In3.Cu" signal "VCC1")
		(10 "In4.Cu" signal "VCC2")
		(12 "In5.Cu" signal "GND2")
		(14 "In6.Cu" signal "IN2")
		(16 "In7.Cu" signal "IN3")
		(18 "In8.Cu" signal "GND3")
		(2 "B.Cu" signal "BOTTOM")
		(9 "F.Adhes" user "F.Adhesive")
		(11 "B.Adhes" user "B.Adhesive")
		(13 "F.Paste" user "Package Geometry/Pastemask Top")
		(15 "B.Paste" user "Package Geometry/Pastemask Bottom")
		(5 "F.SilkS" user "Ref Des/Silkscreen Top")
		(7 "B.SilkS" user "Ref Des/Silkscreen Bottom")
		(1 "F.Mask" user "Board Geometry/Soldermask Top")
		(3 "B.Mask" user "Board Geometry/Soldermask Bottom")
		(17 "Dwgs.User" user "User.Drawings")
		(19 "Cmts.User" user "User.Comments")
		(21 "Eco1.User" user "User.Eco1")
		(23 "Eco2.User" user "User.Eco2")
		(25 "Edge.Cuts" user "Board Geometry/Outline")
		(27 "Margin" user)
		(31 "F.CrtYd" user "Package Geometry/Place Bound Top")
		(29 "B.CrtYd" user "Package Geometry/Place Bound Bottom")
		(35 "F.Fab" user "Ref Des/Assembly Top")
		(33 "B.Fab" user "Ref Des/Assembly Bottom")
	)
	(footprint ""
		(layer "F.Cu")
		(at 19.943826 -100.039678 180)
		(property "Reference" "R1154"
			(at 5.197856 0.42037 0)
			(unlocked yes)
			(layer "F.SilkS")
			(effects
				(font
					(size 0.7874 0.5842)
					(thickness 0.1524)
				)
				(justify left)
			)
		)
		(property "Value" ""
			(at 0 0 180)
			(layer "F.Fab")
			(effects
				(font
					(size 1.27 1.27)
				)
			)
		)
		(duplicate_pad_numbers_are_jumpers no)
		(fp_line
			(start 0.7874 0.4064)
			(end -0.7874 0.4064)
			(stroke
				(width 0.1524)
				(type default)
			)
			(layer "F.SilkS")
		)
		(fp_line
			(start 0.7874 -0.4064)
			(end 0.7874 0.4064)
			(stroke
				(width 0.1524)
				(type default)
			)
			(layer "F.SilkS")
		)
		(fp_line
			(start -0.7874 0.4064)
			(end -0.7874 -0.4064)
			(stroke
				(width 0.1524)
				(type default)
			)
			(layer "F.SilkS")
		)
		(fp_line
			(start -0.7874 -0.4064)
			(end 0.7874 -0.4064)
			(stroke
				(width 0.1524)
				(type default)
			)
			(layer "F.SilkS")
		)
		(fp_poly
			(pts
				(xy -0.508 0.2794) (xy -0.508 0.2286) (xy -0.635 0.2286) (xy -0.635 -0.254) (xy -0.5334 -0.254)
				(xy -0.5334 -0.2794) (xy 0.5334 -0.2794) (xy 0.5334 -0.254) (xy 0.635 -0.254) (xy 0.635 0.254) (xy 0.5334 0.254)
				(xy 0.5334 0.2794)
			)
			(stroke
				(width 0)
				(type default)
			)
			(fill no)
			(layer "F.CrtYd")
		)
		(pad "1" smd rect
			(at 0.40005 0 180)
			(size 0.4572 0.508)
			(layers "F.Cu" "F.Mask" "F.Paste")
			(net "GND")
		)
		(pad "2" smd rect
			(at -0.40005 0 180)
			(size 0.4572 0.508)
			(layers "F.Cu" "F.Mask" "F.Paste")
			(net "FRU_SYS_A2")
		)
	)
	(footprint ""
		(layer "F.Cu")
		(at 62.563502 -160.320736 -90)
		(property "Reference" "R1107"
			(at 4.581398 0.477774 90)
			(unlocked yes)
			(layer "F.SilkS")
			(effects
				(font
					(size 0.7874 0.5842)
					(thickness 0.1524)
				)
				(justify left)
			)
		)
		(property "Value" ""
			(at 0 0 270)
			(layer "F.Fab")
			(effects
				(font
					(size 1.27 1.27)
				)
			)
		)
		(duplicate_pad_numbers_are_jumpers no)
		(fp_line
			(start -0.7874 0.4064)
			(end -0.7874 -0.4064)
			(stroke
				(width 0.1524)
				(type default)
			)
			(layer "F.SilkS")
		)
		(fp_line
			(start 0.7874 0.4064)
			(end -0.7874 0.4064)
			(stroke
				(width 0.1524)
				(type default)
			)
			(layer "F.SilkS")
		)
		(fp_line
			(start -0.7874 -0.4064)
			(end 0.7874 -0.4064)
			(stroke
				(width 0.1524)
				(type default)
			)
			(layer "F.SilkS")
		)
		(fp_line
			(start 0.7874 -0.4064)
			(end 0.7874 0.4064)
			(stroke
				(width 0.1524)
				(type default)
			)
			(layer "F.SilkS")
		)
		(fp_poly
			(pts
				(xy -0.508 0.2794) (xy -0.508 0.2286) (xy -0.635 0.2286) (xy -0.635 -0.254) (xy -0.5334 -0.254)
				(xy -0.5334 -0.2794) (xy 0.5334 -0.2794) (xy 0.5334 -0.254) (xy 0.635 -0.254) (xy 0.635 0.254) (xy 0.5334 0.254)
				(xy 0.5334 0.2794)
			)
			(stroke
				(width 0)
				(type default)
			)
			(fill no)
			(layer "F.CrtYd")
		)
		(pad "1" smd rect
			(at 0.40005 0 270)
			(size 0.4572 0.508)
			(layers "F.Cu" "F.Mask" "F.Paste")
			(net "P12V_AUX")
		)
		(pad "2" smd rect
			(at -0.40005 0 270)
			(size 0.4572 0.508)
			(layers "F.Cu" "F.Mask" "F.Paste")
			(net "FM_CPLD_NODE1_P5V_EN_LV")
		)
	)
	(footprint ""
		(layer "F.Cu")
		(at 53.679598 -108.655866 90)
		(property "Reference" "PL2"
			(at 4.206748 -1.133094 0)
			(unlocked yes)
			(layer "F.SilkS")
			(effects
				(font
					(size 0.7874 0.5842)
					(thickness 0.1524)
				)
				(justify left)
			)
		)
		(property "Value" ""
			(at 0 0 90)
			(layer "F.Fab")
			(effects
				(font
					(size 1.27 1.27)
				)
			)
		)
		(duplicate_pad_numbers_are_jumpers no)
		(fp_line
			(start 3.350006 -4.1656)
			(end 3.350006 4.1656)
			(stroke
				(width 0.1524)
				(type default)
			)
			(layer "F.SilkS")
		)
		(fp_line
			(start -3.350006 -4.1656)
			(end 3.350006 -4.1656)
			(stroke
				(width 0.1524)
				(type default)
			)
			(layer "F.SilkS")
		)
		(fp_line
			(start 3.350006 4.1656)
			(end -3.350006 4.1656)
			(stroke
				(width 0.1524)
				(type default)
			)
			(layer "F.SilkS")
		)
		(fp_line
			(start -3.350006 4.1656)
			(end -3.350006 -4.1656)
			(stroke
				(width 0.1524)
				(type default)
			)
			(layer "F.SilkS")
		)
		(fp_poly
			(pts
				(xy -3.350006 -3.64998) (xy -1.7018 -3.64998) (xy -1.7018 -4.05257) (xy 1.7018 -4.05257) (xy 1.7018 -3.64998)
				(xy 3.350006 -3.64998) (xy 3.350006 3.64998) (xy 1.7018 3.64998) (xy 1.7018 4.05257) (xy -1.7018 4.05257)
				(xy -1.7018 3.64998) (xy -3.350006 3.64998)
			)
			(stroke
				(width 0)
				(type default)
			)
			(fill no)
			(layer "F.CrtYd")
		)
		(fp_line
			(start 3.350006 -3.64998)
			(end 3.350006 3.64998)
			(stroke
				(width 0.1)
				(type default)
			)
			(layer "F.Fab")
		)
		(fp_line
			(start -3.350006 -3.64998)
			(end 3.350006 -3.64998)
			(stroke
				(width 0.1)
				(type default)
			)
			(layer "F.Fab")
		)
		(fp_line
			(start 3.350006 3.64998)
			(end -3.350006 3.64998)
			(stroke
				(width 0.1)
				(type default)
			)
			(layer "F.Fab")
		)
		(fp_line
			(start -3.350006 3.64998)
			(end -3.350006 -3.64998)
			(stroke
				(width 0.1)
				(type default)
			)
			(layer "F.Fab")
		)
		(pad "1" smd rect
			(at 0 -2.92481)
			(size 2.15392 3.302)
			(layers "F.Cu" "F.Mask" "F.Paste")
			(net "SW_P3V3_STB_NODE1_PH")
		)
		(pad "2" smd rect
			(at 0 2.92481)
			(size 2.15392 3.302)
			(layers "F.Cu" "F.Mask" "F.Paste")
			(net "P3V3_STB_NODE1")
		)
	)
)
